# T6G (Grand Teton) — schematic netlist excerpt (pin names and nets, part order shuffled) for the footprints in the layout excerpt that follows; sources: Cadence DE-HDL packaged netlist, KiCad conversion of 04192023_DAF0TMB3IC0_F0TG_MB_C_brd_V02_OCP.brd

PC6520  Q_CAP  22UF 16V 20% X6S  pkg C0805  page 361 : A = SW_P12V_AUX_P1V8_RETIMER_CPU1_FLT ; B = GND
R264  Q_RES  0 5% CHIP  pkg 0402LF  page 82 : A = CPU1_CORETYPE2 ; B = FM_CPU1_CORETYPE2
R8021  Q_RES  0 5% CHIP  pkg 0402LF  page 81 : A = FM_JTAG_BMC_OE ; B = FM_JTAG_BMC_R_OE

(kicad_pcb
	(version 20260206)
	(generator "pcbnew")
	(generator_version "10.0")
	(general
		(thickness 1.6)
		(legacy_teardrops no)
	)
	(paper "A4")
	(title_block
		(title "04192023_DAF0TMB3IC0_F0TG_MB_C_brd_V02_OCP.brd")
		(comment 1 "Grand Teton / footprints 2128-2130 of 8354")
	)
	(layers
		(0 "F.Cu" signal "TOP")
		(4 "In1.Cu" signal "GND")
		(6 "In2.Cu" signal "IN1")
		(8 "In3.Cu" signal "GND1")
		(10 "In4.Cu" signal "IN2")
		(12 "In5.Cu" signal "GND2")
		(14 "In6.Cu" signal "IN3")
		(16 "In7.Cu" signal "GND3")
		(18 "In8.Cu" signal "VCC")
		(20 "In9.Cu" signal "VCC1")
		(22 "In10.Cu" signal "GND4")
		(24 "In11.Cu" signal "IN4")
		(26 "In12.Cu" signal "GND5")
		(28 "In13.Cu" signal "IN5")
		(30 "In14.Cu" signal "GND6")
		(32 "In15.Cu" signal "IN6")
		(34 "In16.Cu" signal "GND7")
		(2 "B.Cu" signal "BOTTOM")
		(9 "F.Adhes" user "F.Adhesive")
		(11 "B.Adhes" user "B.Adhesive")
		(13 "F.Paste" user "Package Geometry/Pastemask Top")
		(15 "B.Paste" user "Package Geometry/Pastemask Bottom")
		(5 "F.SilkS" user "Ref Des/Silkscreen Top")
		(7 "B.SilkS" user "Ref Des/Silkscreen Bottom")
		(1 "F.Mask" user "Board Geometry/Soldermask Top")
		(3 "B.Mask" user "Board Geometry/Soldermask Bottom")
		(17 "Dwgs.User" user "User.Drawings")
		(19 "Cmts.User" user "User.Comments")
		(21 "Eco1.User" user "User.Eco1")
		(23 "Eco2.User" user "User.Eco2")
		(25 "Edge.Cuts" user "Board Geometry/Outline")
		(27 "Margin" user)
		(31 "F.CrtYd" user "Package Geometry/Place Bound Top")
		(29 "B.CrtYd" user "Package Geometry/Place Bound Bottom")
		(35 "F.Fab" user "Ref Des/Assembly Top")
		(33 "B.Fab" user "Ref Des/Assembly Bottom")
	)
	(footprint ""
		(layer "F.Cu")
		(at 201.041 -128.778)
		(property "Reference" "R8021"
			(at 0 0 0)
			(layer "F.SilkS")
			(hide yes)
			(effects
				(font
					(size 1.27 1.27)
				)
			)
		)
		(property "Value" ""
			(at 0 0 0)
			(layer "F.Fab")
			(effects
				(font
					(size 1.27 1.27)
				)
			)
		)
		(duplicate_pad_numbers_are_jumpers no)
		(fp_line
			(start -0.7874 -0.4064)
			(end 0.7874 -0.4064)
			(stroke
				(width 0.1524)
				(type default)
			)
			(layer "F.SilkS")
		)
		(fp_line
			(start -0.7874 0.4064)
			(end -0.7874 -0.4064)
			(stroke
				(width 0.1524)
				(type default)
			)
			(layer "F.SilkS")
		)
		(fp_line
			(start 0.7874 -0.4064)
			(end 0.7874 0.4064)
			(stroke
				(width 0.1524)
				(type default)
			)
			(layer "F.SilkS")
		)
		(fp_line
			(start 0.7874 0.4064)
			(end -0.7874 0.4064)
			(stroke
				(width 0.1524)
				(type default)
			)
			(layer "F.SilkS")
		)
		(fp_line
			(start -0.67945 -0.305054)
			(end -0.12065 -0.305054)
			(stroke
				(width 0.1)
				(type default)
			)
			(layer "F.Fab")
		)
		(fp_line
			(start -0.67945 0.3048)
			(end -0.67945 -0.305054)
			(stroke
				(width 0.1)
				(type default)
			)
			(layer "F.Fab")
		)
		(fp_line
			(start -0.12065 -0.305054)
			(end -0.12065 -0.2794)
			(stroke
				(width 0.1)
				(type default)
			)
			(layer "F.Fab")
		)
		(fp_line
			(start -0.12065 -0.2794)
			(end 0.12065 -0.2794)
			(stroke
				(width 0.1)
				(type default)
			)
			(layer "F.Fab")
		)
		(fp_line
			(start -0.12065 0.2794)
			(end -0.12065 0.3048)
			(stroke
				(width 0.1)
				(type default)
			)
			(layer "F.Fab")
		)
		(fp_line
			(start -0.12065 0.3048)
			(end -0.67945 0.3048)
			(stroke
				(width 0.1)
				(type default)
			)
			(layer "F.Fab")
		)
		(fp_line
			(start 0.120396 0.2794)
			(end -0.12065 0.2794)
			(stroke
				(width 0.1)
				(type default)
			)
			(layer "F.Fab")
		)
		(fp_line
			(start 0.120396 0.3048)
			(end 0.120396 0.2794)
			(stroke
				(width 0.1)
				(type default)
			)
			(layer "F.Fab")
		)
		(fp_line
			(start 0.12065 -0.3048)
			(end 0.67945 -0.3048)
			(stroke
				(width 0.1)
				(type default)
			)
			(layer "F.Fab")
		)
		(fp_line
			(start 0.12065 -0.2794)
			(end 0.12065 -0.3048)
			(stroke
				(width 0.1)
				(type default)
			)
			(layer "F.Fab")
		)
		(fp_line
			(start 0.67945 -0.3048)
			(end 0.67945 0.3048)
			(stroke
				(width 0.1)
				(type default)
			)
			(layer "F.Fab")
		)
		(fp_line
			(start 0.67945 0.3048)
			(end 0.120396 0.3048)
			(stroke
				(width 0.1)
				(type default)
			)
			(layer "F.Fab")
		)
		(pad "1" smd circle
			(at -0.40005 0)
			(size 0 0)
			(layers "F.Cu" "F.Mask" "F.Paste")
			(net "FM_JTAG_BMC_OE")
		)
		(pad "2" smd circle
			(at 0.40005 0)
			(size 0 0)
			(layers "F.Cu" "F.Mask" "F.Paste")
			(net "FM_JTAG_BMC_R_OE")
		)
	)
	(footprint ""
		(layer "F.Cu")
		(at 191.897 -100.294948 90)
		(property "Reference" "R264"
			(at 0 0 90)
			(layer "F.SilkS")
			(hide yes)
			(effects
				(font
					(size 1.27 1.27)
				)
			)
		)
		(property "Value" ""
			(at 0 0 90)
			(layer "F.Fab")
			(effects
				(font
					(size 1.27 1.27)
				)
			)
		)
		(duplicate_pad_numbers_are_jumpers no)
		(fp_line
			(start 0.7874 -0.4064)
			(end 0.7874 0.4064)
			(stroke
				(width 0.1524)
				(type default)
			)
			(layer "F.SilkS")
		)
		(fp_line
			(start -0.7874 -0.4064)
			(end 0.7874 -0.4064)
			(stroke
				(width 0.1524)
				(type default)
			)
			(layer "F.SilkS")
		)
		(fp_line
			(start 0.7874 0.4064)
			(end -0.7874 0.4064)
			(stroke
				(width 0.1524)
				(type default)
			)
			(layer "F.SilkS")
		)
		(fp_line
			(start -0.7874 0.4064)
			(end -0.7874 -0.4064)
			(stroke
				(width 0.1524)
				(type default)
			)
			(layer "F.SilkS")
		)
		(fp_line
			(start -0.12065 -0.305054)
			(end -0.12065 -0.2794)
			(stroke
				(width 0.1)
				(type default)
			)
			(layer "F.Fab")
		)
		(fp_line
			(start -0.67945 -0.305054)
			(end -0.12065 -0.305054)
			(stroke
				(width 0.1)
				(type default)
			)
			(layer "F.Fab")
		)
		(fp_line
			(start 0.67945 -0.3048)
			(end 0.67945 0.3048)
			(stroke
				(width 0.1)
				(type default)
			)
			(layer "F.Fab")
		)
		(fp_line
			(start 0.12065 -0.3048)
			(end 0.67945 -0.3048)
			(stroke
				(width 0.1)
				(type default)
			)
			(layer "F.Fab")
		)
		(fp_line
			(start 0.12065 -0.2794)
			(end 0.12065 -0.3048)
			(stroke
				(width 0.1)
				(type default)
			)
			(layer "F.Fab")
		)
		(fp_line
			(start -0.12065 -0.2794)
			(end 0.12065 -0.2794)
			(stroke
				(width 0.1)
				(type default)
			)
			(layer "F.Fab")
		)
		(fp_line
			(start 0.120396 0.2794)
			(end -0.12065 0.2794)
			(stroke
				(width 0.1)
				(type default)
			)
			(layer "F.Fab")
		)
		(fp_line
			(start -0.12065 0.2794)
			(end -0.12065 0.3048)
			(stroke
				(width 0.1)
				(type default)
			)
			(layer "F.Fab")
		)
		(fp_line
			(start 0.67945 0.3048)
			(end 0.120396 0.3048)
			(stroke
				(width 0.1)
				(type default)
			)
			(layer "F.Fab")
		)
		(fp_line
			(start 0.120396 0.3048)
			(end 0.120396 0.2794)
			(stroke
				(width 0.1)
				(type default)
			)
			(layer "F.Fab")
		)
		(fp_line
			(start -0.12065 0.3048)
			(end -0.67945 0.3048)
			(stroke
				(width 0.1)
				(type default)
			)
			(layer "F.Fab")
		)
		(fp_line
			(start -0.67945 0.3048)
			(end -0.67945 -0.305054)
			(stroke
				(width 0.1)
				(type default)
			)
			(layer "F.Fab")
		)
		(pad "1" smd circle
			(at -0.40005 0 90)
			(size 0 0)
			(layers "F.Cu" "F.Mask" "F.Paste")
			(net "CPU1_CORETYPE2")
		)
		(pad "2" smd circle
			(at 0.40005 0 90)
			(size 0 0)
			(layers "F.Cu" "F.Mask" "F.Paste")
			(net "FM_CPU1_CORETYPE2")
		)
	)
	(footprint ""
		(layer "F.Cu")
		(at 229.87 -283.917898 180)
		(property "Reference" "PC6520"
			(at 0 0 180)
			(layer "F.SilkS")
			(hide yes)
			(effects
				(font
					(size 1.27 1.27)
				)
			)
		)
		(property "Value" ""
			(at 0 0 180)
			(layer "F.Fab")
			(effects
				(font
					(size 1.27 1.27)
				)
			)
		)
		(duplicate_pad_numbers_are_jumpers no)
		(fp_line
			(start 1.524 0.762)
			(end -1.524 0.762)
			(stroke
				(width 0.1524)
				(type default)
			)
			(layer "F.SilkS")
		)
		(fp_line
			(start 1.524 -0.762)
			(end 1.524 0.762)
			(stroke
				(width 0.1524)
				(type default)
			)
			(layer "F.SilkS")
		)
		(fp_line
			(start -1.524 0.762)
			(end -1.524 -0.762)
			(stroke
				(width 0.1524)
				(type default)
			)
			(layer "F.SilkS")
		)
		(fp_line
			(start -1.524 -0.762)
			(end 1.524 -0.762)
			(stroke
				(width 0.1524)
				(type default)
			)
			(layer "F.SilkS")
		)
		(fp_line
			(start 1.1049 0.724916)
			(end 1.1049 -0.724916)
			(stroke
				(width 0.1)
				(type default)
			)
			(layer "F.Fab")
		)
		(fp_line
			(start 1.1049 -0.724916)
			(end -1.1049 -0.724916)
			(stroke
				(width 0.1)
				(type default)
			)
			(layer "F.Fab")
		)
		(fp_line
			(start -1.1049 0.724916)
			(end 1.1049 0.724916)
			(stroke
				(width 0.1)
				(type default)
			)
			(layer "F.Fab")
		)
		(fp_line
			(start -1.1049 -0.724916)
			(end -1.1049 0.724916)
			(stroke
				(width 0.1)
				(type default)
			)
			(layer "F.Fab")
		)
		(pad "1" smd rect
			(at -0.889 0)
			(size 1.016 1.27)
			(layers "F.Cu" "F.Mask" "F.Paste")
			(net "SW_P12V_AUX_P1V8_RETIMER_CPU1_FLT")
		)
		(pad "2" smd rect
			(at 0.889 0)
			(size 1.016 1.27)
			(layers "F.Cu" "F.Mask" "F.Paste")
			(net "GND")
		)
	)
)
